# TIMECARD (Time Appliance Project (Time Card)) — schematic netlist excerpt (pin names and nets, part order shuffled) for the footprints in the layout excerpt that follows; sources: Cadence DE-HDL packaged netlist, KiCad conversion of R4006-B0001-02_R01.brd

R304  RESISTOR  4.7KOHM 1%  pkg SMC_0402R_H016  page 20 : \1\ = XP3R3V_FPGA ; \2\ = R_BNO080_BOOT_N
R6  RESISTOR  20OHM 1%  pkg SMC_0402R_H016  page 32 : \1\ = XP5R0V ; \2\ = UNNAMED_516_CAPACITOR_I29_1

(kicad_pcb
	(version 20260206)
	(generator "pcbnew")
	(generator_version "10.0")
	(general
		(thickness 1.6)
		(legacy_teardrops no)
	)
	(paper "A4")
	(title_block
		(title "timecard-production-celestica-r4006 — R4006-B0001-02_R01.brd")
		(comment 1 "Time Appliance Project (Time Card) / footprints 615-616 of 1113")
	)
	(layers
		(0 "F.Cu" signal "TOP")
		(4 "In1.Cu" signal "L02_GND1")
		(6 "In2.Cu" signal "L03_SIG1")
		(8 "In3.Cu" signal "L04_GND2")
		(10 "In4.Cu" signal "L05_VCC1")
		(12 "In5.Cu" signal "L06_VCC2")
		(14 "In6.Cu" signal "L07_GND3")
		(16 "In7.Cu" signal "L08_SIG2")
		(18 "In8.Cu" signal "L09_GND4")
		(2 "B.Cu" signal "BOTTOM")
		(9 "F.Adhes" user "F.Adhesive")
		(11 "B.Adhes" user "B.Adhesive")
		(13 "F.Paste" user "Package Geometry/Pastemask Top")
		(15 "B.Paste" user "Package Geometry/Pastemask Bottom")
		(5 "F.SilkS" user "Ref Des/Silkscreen Top")
		(7 "B.SilkS" user "Ref Des/Silkscreen Bottom")
		(1 "F.Mask" user "Board Geometry/Soldermask Top")
		(3 "B.Mask" user "Board Geometry/Soldermask Bottom")
		(17 "Dwgs.User" user "User.Drawings")
		(19 "Cmts.User" user "User.Comments")
		(21 "Eco1.User" user "User.Eco1")
		(23 "Eco2.User" user "User.Eco2")
		(25 "Edge.Cuts" user "Board Geometry/Outline")
		(27 "Margin" user)
		(31 "F.CrtYd" user "Package Geometry/Place Bound Top")
		(29 "B.CrtYd" user "Package Geometry/Place Bound Bottom")
		(35 "F.Fab" user "Ref Des/Assembly Top")
		(33 "B.Fab" user "Ref Des/Assembly Bottom")
	)
	(footprint ""
		(layer "F.Cu")
		(at 35.179 -104.267 -90)
		(property "Reference" "R6"
			(at -1.397 4.02463 90)
			(unlocked yes)
			(layer "F.SilkS")
			(effects
				(font
					(size 0.7874 0.5842)
					(thickness 0.1524)
				)
			)
		)
		(property "Value" "VAL*"
			(at 0.02032 2.13233 270)
			(unlocked yes)
			(layer "F.Fab")
			(hide yes)
			(effects
				(font
					(size 0.7874 0.5842)
					(thickness 0.1524)
				)
			)
		)
		(property "Device Type" "RESISTOR-G155-120R0-01,20OHM,1%"
			(at 0.008382 1.210564 270)
			(unlocked yes)
			(layer "F.Fab")
			(hide yes)
			(effects
				(font
					(size 0.7874 0.5842)
					(thickness 0.1524)
				)
			)
		)
		(property "User Part Number" "PARTNUM*"
			(at 0.02032 4.024884 270)
			(unlocked yes)
			(layer "Cmts.User")
			(hide yes)
			(effects
				(font
					(size 0.7874 0.5842)
					(thickness 0.1524)
				)
			)
		)
		(property "Tolerance" "TOL*"
			(at 0.044704 3.05435 270)
			(unlocked yes)
			(layer "Cmts.User")
			(hide yes)
			(effects
				(font
					(size 0.7874 0.5842)
					(thickness 0.1524)
				)
			)
		)
		(duplicate_pad_numbers_are_jumpers no)
		(fp_line
			(start -1.143 0.5588)
			(end 1.143 0.5588)
			(stroke
				(width 0.1)
				(type default)
			)
			(layer "F.SilkS")
		)
		(fp_line
			(start 1.143 0.5588)
			(end 1.143 -0.5588)
			(stroke
				(width 0.1)
				(type default)
			)
			(layer "F.SilkS")
		)
		(fp_line
			(start -1.143 -0.5588)
			(end -1.143 0.5588)
			(stroke
				(width 0.1)
				(type default)
			)
			(layer "F.SilkS")
		)
		(fp_line
			(start 1.143 -0.5588)
			(end -1.143 -0.5588)
			(stroke
				(width 0.1)
				(type default)
			)
			(layer "F.SilkS")
		)
		(fp_rect
			(start -1.143 -0.5588)
			(end 1.143 0.5588)
			(stroke
				(width 0)
				(type default)
			)
			(fill no)
			(layer "F.CrtYd")
		)
		(fp_line
			(start -0.508 0.3048)
			(end 0.508 0.3048)
			(stroke
				(width 0.1)
				(type default)
			)
			(layer "F.Fab")
		)
		(fp_line
			(start 0.508 0.3048)
			(end 0.508 -0.3048)
			(stroke
				(width 0.1)
				(type default)
			)
			(layer "F.Fab")
		)
		(fp_line
			(start -0.508 -0.3048)
			(end -0.508 0.3048)
			(stroke
				(width 0.1)
				(type default)
			)
			(layer "F.Fab")
		)
		(fp_line
			(start 0.508 -0.3048)
			(end -0.508 -0.3048)
			(stroke
				(width 0.1)
				(type default)
			)
			(layer "F.Fab")
		)
		(pad "1" smd rect
			(at -0.5334 0 270)
			(size 0.7112 0.6096)
			(layers "F.Cu" "F.Mask" "F.Paste")
			(net "XP5R0V")
		)
		(pad "2" smd rect
			(at 0.5334 0 270)
			(size 0.7112 0.6096)
			(layers "F.Cu" "F.Mask" "F.Paste")
			(net "UNNAMED_516_CAPACITOR_I29_1")
		)
		(zone
			(layer "F.Cu")
			(hatch none 0.5)
			(connect_pads
				(clearance 0)
			)
			(min_thickness 0.25)
			(keepout
				(tracks allowed)
				(vias not_allowed)
				(pads allowed)
				(copperpour not_allowed)
				(footprints allowed)
			)
			(placement
				(enabled no)
				(sheetname "")
			)
			(fill
				(thermal_gap 0.5)
				(thermal_bridge_width 0.5)
				(island_removal_mode 0)
			)
			(polygon
				(pts
					(xy 35.4838 -104.3432) (xy 34.8742 -104.3432) (xy 34.8742 -104.1908) (xy 35.4838 -104.1908)
				)
			)
		)
	)
	(footprint ""
		(layer "F.Cu")
		(at 84.709 -64.3128 -90)
		(property "Reference" "R304"
			(at -13.4112 9.99363 90)
			(unlocked yes)
			(layer "F.SilkS")
			(effects
				(font
					(size 0.7874 0.5842)
					(thickness 0.1524)
				)
			)
		)
		(property "Value" "VAL*"
			(at 0.02032 2.13233 270)
			(unlocked yes)
			(layer "F.Fab")
			(hide yes)
			(effects
				(font
					(size 0.7874 0.5842)
					(thickness 0.1524)
				)
			)
		)
		(property "Device Type" "RESISTOR-G155-14701-01,4.7KOHMA"
			(at 0.008382 1.210564 270)
			(unlocked yes)
			(layer "F.Fab")
			(hide yes)
			(effects
				(font
					(size 0.7874 0.5842)
					(thickness 0.1524)
				)
			)
		)
		(property "User Part Number" "PARTNUM*"
			(at 0.02032 4.024884 270)
			(unlocked yes)
			(layer "Cmts.User")
			(hide yes)
			(effects
				(font
					(size 0.7874 0.5842)
					(thickness 0.1524)
				)
			)
		)
		(property "Tolerance" "TOL*"
			(at 0.044704 3.05435 270)
			(unlocked yes)
			(layer "Cmts.User")
			(hide yes)
			(effects
				(font
					(size 0.7874 0.5842)
					(thickness 0.1524)
				)
			)
		)
		(duplicate_pad_numbers_are_jumpers no)
		(fp_line
			(start -1.143 0.5588)
			(end 1.143 0.5588)
			(stroke
				(width 0.1)
				(type default)
			)
			(layer "F.SilkS")
		)
		(fp_line
			(start 1.143 0.5588)
			(end 1.143 -0.5588)
			(stroke
				(width 0.1)
				(type default)
			)
			(layer "F.SilkS")
		)
		(fp_line
			(start -1.143 -0.5588)
			(end -1.143 0.5588)
			(stroke
				(width 0.1)
				(type default)
			)
			(layer "F.SilkS")
		)
		(fp_line
			(start 1.143 -0.5588)
			(end -1.143 -0.5588)
			(stroke
				(width 0.1)
				(type default)
			)
			(layer "F.SilkS")
		)
		(fp_rect
			(start 1.143 0.5588)
			(end -1.143 -0.5588)
			(stroke
				(width 0)
				(type default)
			)
			(fill no)
			(layer "F.CrtYd")
		)
		(fp_line
			(start -0.508 0.3048)
			(end 0.508 0.3048)
			(stroke
				(width 0.1)
				(type default)
			)
			(layer "F.Fab")
		)
		(fp_line
			(start 0.508 0.3048)
			(end 0.508 -0.3048)
			(stroke
				(width 0.1)
				(type default)
			)
			(layer "F.Fab")
		)
		(fp_line
			(start -0.508 -0.3048)
			(end -0.508 0.3048)
			(stroke
				(width 0.1)
				(type default)
			)
			(layer "F.Fab")
		)
		(fp_line
			(start 0.508 -0.3048)
			(end -0.508 -0.3048)
			(stroke
				(width 0.1)
				(type default)
			)
			(layer "F.Fab")
		)
		(pad "1" smd rect
			(at -0.5334 0 270)
			(size 0.7112 0.6096)
			(layers "F.Cu" "F.Mask" "F.Paste")
			(net "XP3R3V_FPGA")
		)
		(pad "2" smd rect
			(at 0.5334 0 270)
			(size 0.7112 0.6096)
			(layers "F.Cu" "F.Mask" "F.Paste")
			(net "R_BNO080_BOOT_N")
		)
		(zone
			(layer "F.Cu")
			(hatch none 0.5)
			(connect_pads
				(clearance 0)
			)
			(min_thickness 0.25)
			(keepout
				(tracks allowed)
				(vias not_allowed)
				(pads allowed)
				(copperpour not_allowed)
				(footprints allowed)
			)
			(placement
				(enabled no)
				(sheetname "")
			)
			(fill
				(thermal_gap 0.5)
				(thermal_bridge_width 0.5)
				(island_removal_mode 0)
			)
			(polygon
				(pts
					(xy 84.4042 -64.2366) (xy 85.0138 -64.2366) (xy 85.0138 -64.389) (xy 84.4042 -64.389)
				)
			)
		)
	)
)
